# S9S_MB_2U (Grand Teton) — schematic netlist excerpt (pin names and nets, part order shuffled) for the footprints in the layout excerpt that follows; sources: Cadence DE-HDL packaged netlist, KiCad conversion of 03242023_DA0F0TMBIJ0_F0T_Motherboard_J_brd_V01_OCP.brd

JP15_23  TP  NA  pkg TP_BOM ONLY  page 312 : TP = NC

PU26_P1_5  ISL99390FRZTR5935  ISL99390FRZ-TR5935 IC  pkg QFN21_6X5XB  page 287
  VOS  = PVCCIN_CPU1_VOS5
  AGND  = GND
  VCC  = PVCCIN_CPU1_VDD5
  PVCC  = PVCCIN_CPU1_PVCC
  PGND1  = GND
  GL1  = NC
  PGND2  = GND
  SW  = SW_PVCCIN_CPU1_SW5
  VIN1  = SW_P12V_PVCCIN_CPU1_FLT
  VIN2  = SW_P12V_PVCCIN_CPU1_FLT
  DNC  = NC
  PHASE  = SW_PVCCIN_CPU1_BOOTR5
  BOOT  = SW_PVCCIN_CPU1_BOOT5
  PWM  = PVCCIN_CPU1_PWM5
  EN  = PVCCIN_CPU1_VDD5
  TOUT_FLT  = PVCCIN_CPU1_ATSEN
  LSET  = PVCCIN_CPU1_LSET5
  IOUT  = PVCCIN_CPU1_IMON5
  REFIN  = PVCCIN_CPU1_VREF
  PGND3  = GND
  GL2  = NC

(kicad_pcb
	(version 20260206)
	(generator "pcbnew")
	(generator_version "10.0")
	(general
		(thickness 1.6)
		(legacy_teardrops no)
	)
	(paper "A4")
	(title_block
		(title "03242023_DA0F0TMBIJ0_F0T_Motherboard_J_brd_V01_OCP.brd")
		(comment 1 "Grand Teton / footprints 3272-3273 of 6105")
	)
	(layers
		(0 "F.Cu" signal "TOP")
		(4 "In1.Cu" signal "GND")
		(6 "In2.Cu" signal "IN1")
		(8 "In3.Cu" signal "GND1")
		(10 "In4.Cu" signal "IN2")
		(12 "In5.Cu" signal "GND2")
		(14 "In6.Cu" signal "IN3")
		(16 "In7.Cu" signal "GND3")
		(18 "In8.Cu" signal "VCC")
		(20 "In9.Cu" signal "VCC1")
		(22 "In10.Cu" signal "GND4")
		(24 "In11.Cu" signal "IN4")
		(26 "In12.Cu" signal "GND5")
		(28 "In13.Cu" signal "IN5")
		(30 "In14.Cu" signal "GND6")
		(32 "In15.Cu" signal "IN6")
		(34 "In16.Cu" signal "GND7")
		(2 "B.Cu" signal "BOTTOM")
		(9 "F.Adhes" user "F.Adhesive")
		(11 "B.Adhes" user "B.Adhesive")
		(13 "F.Paste" user "Package Geometry/Pastemask Top")
		(15 "B.Paste" user "Package Geometry/Pastemask Bottom")
		(5 "F.SilkS" user "Ref Des/Silkscreen Top")
		(7 "B.SilkS" user "Ref Des/Silkscreen Bottom")
		(1 "F.Mask" user "Board Geometry/Soldermask Top")
		(3 "B.Mask" user "Board Geometry/Soldermask Bottom")
		(17 "Dwgs.User" user "User.Drawings")
		(19 "Cmts.User" user "User.Comments")
		(21 "Eco1.User" user "User.Eco1")
		(23 "Eco2.User" user "User.Eco2")
		(25 "Edge.Cuts" user "Board Geometry/Outline")
		(27 "Margin" user)
		(31 "F.CrtYd" user "Package Geometry/Place Bound Top")
		(29 "B.CrtYd" user "Package Geometry/Place Bound Bottom")
		(35 "F.Fab" user "Ref Des/Assembly Top")
		(33 "B.Fab" user "Ref Des/Assembly Bottom")
	)
	(footprint ""
		(layer "F.Cu")
		(at 129.639822 -337.126326)
		(property "Reference" "PU26_P1_5"
			(at -3.267202 -6.948932 0)
			(unlocked yes)
			(layer "F.SilkS")
			(effects
				(font
					(size 0.7874 0.5842)
					(thickness 0.1524)
				)
				(justify left)
			)
		)
		(property "Value" ""
			(at 0 0 0)
			(layer "F.Fab")
			(effects
				(font
					(size 1.27 1.27)
				)
			)
		)
		(duplicate_pad_numbers_are_jumpers no)
		(fp_line
			(start -2.500122 -2.999994)
			(end -2.24409 -2.999994)
			(stroke
				(width 0.1524)
				(type default)
			)
			(layer "F.SilkS")
		)
		(fp_line
			(start -2.500122 -2.529078)
			(end -2.500122 -2.999994)
			(stroke
				(width 0.1524)
				(type default)
			)
			(layer "F.SilkS")
		)
		(fp_line
			(start -2.500122 0.6604)
			(end -2.500122 0.229108)
			(stroke
				(width 0.1524)
				(type default)
			)
			(layer "F.SilkS")
		)
		(fp_line
			(start -2.500122 2.999994)
			(end -2.500122 2.339594)
			(stroke
				(width 0.1524)
				(type default)
			)
			(layer "F.SilkS")
		)
		(fp_line
			(start -2.2987 2.999994)
			(end -2.500122 2.999994)
			(stroke
				(width 0.1524)
				(type default)
			)
			(layer "F.SilkS")
		)
		(fp_line
			(start 2.31394 -2.999994)
			(end 2.500122 -2.999994)
			(stroke
				(width 0.1524)
				(type default)
			)
			(layer "F.SilkS")
		)
		(fp_line
			(start 2.500122 -2.999994)
			(end 2.500122 -2.44348)
			(stroke
				(width 0.1524)
				(type default)
			)
			(layer "F.SilkS")
		)
		(fp_line
			(start 2.500122 2.339594)
			(end 2.500122 2.999994)
			(stroke
				(width 0.1524)
				(type default)
			)
			(layer "F.SilkS")
		)
		(fp_line
			(start 2.500122 2.999994)
			(end 2.2987 2.999994)
			(stroke
				(width 0.1524)
				(type default)
			)
			(layer "F.SilkS")
		)
		(fp_poly
			(pts
				(xy -2.181606 -3.555492) (xy -2.689606 -2.539492) (xy -3.197606 -3.555492)
			)
			(stroke
				(width 0)
				(type default)
			)
			(fill yes)
			(layer "F.SilkS")
		)
		(fp_line
			(start -2.500122 -2.999994)
			(end 2.500122 -2.999994)
			(stroke
				(width 0.1)
				(type default)
			)
			(layer "F.Fab")
		)
		(fp_line
			(start -2.500122 2.999994)
			(end -2.500122 -2.999994)
			(stroke
				(width 0.1)
				(type default)
			)
			(layer "F.Fab")
		)
		(fp_line
			(start 2.500122 -2.999994)
			(end 2.500122 2.999994)
			(stroke
				(width 0.1)
				(type default)
			)
			(layer "F.Fab")
		)
		(fp_line
			(start 2.500122 2.999994)
			(end -2.500122 2.999994)
			(stroke
				(width 0.1)
				(type default)
			)
			(layer "F.Fab")
		)
		(fp_poly
			(pts
				(xy -4.218432 -2.783078) (xy -4.218432 -1.767078) (xy -3.202432 -2.275078)
			)
			(stroke
				(width 0)
				(type default)
			)
			(fill yes)
			(layer "F.Fab")
		)
		(pad "1" smd rect
			(at -2.400046 -2.275078 90)
			(size 0.2286 0.6096)
			(layers "F.Cu" "F.Mask" "F.Paste")
			(net "PVCCIN_CPU1_VOS5")
		)
		(pad "2" smd rect
			(at -2.400046 -1.82499 90)
			(size 0.2286 0.6096)
			(layers "F.Cu" "F.Mask" "F.Paste")
			(net "GND")
		)
		(pad "3" smd rect
			(at -2.400046 -1.374902 90)
			(size 0.2286 0.6096)
			(layers "F.Cu" "F.Mask" "F.Paste")
			(net "PVCCIN_CPU1_VDD5")
		)
		(pad "4" smd rect
			(at -2.400046 -0.925068 90)
			(size 0.2286 0.6096)
			(layers "F.Cu" "F.Mask" "F.Paste")
			(net "PVCCIN_CPU1_PVCC")
		)
		(pad "5" smd rect
			(at -2.400046 -0.47498 90)
			(size 0.2286 0.6096)
			(layers "F.Cu" "F.Mask" "F.Paste")
			(net "GND")
		)
		(pad "6" smd rect
			(at -2.400046 -0.024892 90)
			(size 0.2286 0.6096)
			(layers "F.Cu" "F.Mask" "F.Paste")
			(net "Net_8532")
		)
		(pad "7_9-20_24" smd circle
			(at 0 1.150112 90)
			(size 0 0)
			(layers "F.Cu" "F.Mask" "F.Paste")
			(net "GND")
		)
		(pad "10_19" smd rect
			(at 0 2.899918 90)
			(size 0.6096 4.318)
			(layers "F.Cu" "F.Mask" "F.Paste")
			(net "SW_PVCCIN_CPU1_SW5")
		)
		(pad "25_29" smd rect
			(at 1.549908 -1.279906 270)
			(size 2.0574 2.3114)
			(layers "F.Cu" "F.Mask" "F.Paste")
			(net "SW_P12V_PVCCIN_CPU1_FLT")
		)
		(pad "30" smd rect
			(at 2.05994 -2.899918)
			(size 0.2286 0.6096)
			(layers "F.Cu" "F.Mask" "F.Paste")
			(net "SW_P12V_PVCCIN_CPU1_FLT")
		)
		(pad "31" smd rect
			(at 1.610106 -2.899918)
			(size 0.2286 0.6096)
			(layers "F.Cu" "F.Mask" "F.Paste")
			(net "Net_8533")
		)
		(pad "32" smd rect
			(at 1.160018 -2.899918)
			(size 0.2286 0.6096)
			(layers "F.Cu" "F.Mask" "F.Paste")
			(net "SW_PVCCIN_CPU1_BOOTR5")
		)
		(pad "33" smd rect
			(at 0.70993 -2.899918)
			(size 0.2286 0.6096)
			(layers "F.Cu" "F.Mask" "F.Paste")
			(net "SW_PVCCIN_CPU1_BOOT5")
		)
		(pad "34" smd rect
			(at 0.260096 -2.899918)
			(size 0.2286 0.6096)
			(layers "F.Cu" "F.Mask" "F.Paste")
			(net "PVCCIN_CPU1_PWM5")
		)
		(pad "35" smd rect
			(at -0.189992 -2.899918)
			(size 0.2286 0.6096)
			(layers "F.Cu" "F.Mask" "F.Paste")
			(net "PVCCIN_CPU1_VDD5")
		)
		(pad "36" smd rect
			(at -0.64008 -2.899918)
			(size 0.2286 0.6096)
			(layers "F.Cu" "F.Mask" "F.Paste")
			(net "PVCCIN_CPU1_ATSEN")
		)
		(pad "37" smd rect
			(at -1.089914 -2.899918)
			(size 0.2286 0.6096)
			(layers "F.Cu" "F.Mask" "F.Paste")
			(net "PVCCIN_CPU1_LSET5")
		)
		(pad "38" smd rect
			(at -1.540002 -2.899918)
			(size 0.2286 0.6096)
			(layers "F.Cu" "F.Mask" "F.Paste")
			(net "PVCCIN_CPU1_IMON5")
		)
		(pad "39" smd rect
			(at -1.99009 -2.899918)
			(size 0.2286 0.6096)
			(layers "F.Cu" "F.Mask" "F.Paste")
			(net "PVCCIN_CPU1_VREF")
		)
		(pad "40" smd rect
			(at -0.87503 -1.27508)
			(size 1.7526 1.9558)
			(layers "F.Cu" "F.Mask" "F.Paste")
			(net "GND")
		)
		(pad "41" smd rect
			(at -1.525016 0.249936 270)
			(size 0.3048 0.4572)
			(layers "F.Cu" "F.Mask" "F.Paste")
			(net "Net_8531")
		)
		(zone
			(layer "F.Cu")
			(hatch none 0.5)
			(connect_pads
				(clearance 0)
			)
			(min_thickness 0.25)
			(keepout
				(tracks not_allowed)
				(vias allowed)
				(pads allowed)
				(copperpour not_allowed)
				(footprints allowed)
			)
			(placement
				(enabled no)
				(sheetname "")
			)
			(fill
				(thermal_gap 0.5)
				(thermal_bridge_width 0.5)
				(island_removal_mode 0)
			)
			(polygon
				(pts
					(xy 127.595376 -338.699348) (xy 127.837692 -338.699348) (xy 127.837692 -337.746848) (xy 127.595376 -337.746848)
				)
			)
		)
		(zone
			(layer "F.Cu")
			(hatch none 0.5)
			(connect_pads
				(clearance 0)
			)
			(min_thickness 0.25)
			(keepout
				(tracks not_allowed)
				(vias allowed)
				(pads allowed)
				(copperpour not_allowed)
				(footprints allowed)
			)
			(placement
				(enabled no)
				(sheetname "")
			)
			(fill
				(thermal_gap 0.5)
				(thermal_bridge_width 0.5)
				(island_removal_mode 0)
			)
			(polygon
				(pts
					(xy 127.1397 -334.126332) (xy 127.1397 -334.875632) (xy 132.139944 -334.875632) (xy 132.139944 -334.126332)
					(xy 131.849622 -334.126332) (xy 131.849622 -334.582008) (xy 127.430022 -334.582008) (xy 127.430022 -334.126332)
				)
			)
		)
	)
	(footprint ""
		(layer "F.Cu")
		(at 502.47169 -469.569546)
		(property "Reference" "JP15_23"
			(at -1.6764 -1.07823 0)
			(unlocked yes)
			(layer "F.SilkS")
			(effects
				(font
					(size 0.7874 0.5842)
					(thickness 0.1524)
				)
				(justify left)
			)
		)
		(property "Value" ""
			(at 0 0 0)
			(layer "F.Fab")
			(effects
				(font
					(size 1.27 1.27)
				)
			)
		)
		(duplicate_pad_numbers_are_jumpers no)
		(pad "1" smd circle
			(at 0 0)
			(size 0.762 0.762)
			(layers "F.Cu" "F.Mask" "F.Paste")
			(net "Net_8622")
		)
	)
)
